(kicad_pcb
	(version 20260206)
	(generator "pcbnew")
	(generator_version "10.0")
	(general
		(thickness 1.6)
		(legacy_teardrops no)
	)
	(paper "A4")
	(title_block
		(title "netronome-mezz — pcbd0082-001_rev01_jul9_a.brd")
		(comment 1 "Open CloudServer (Microsoft) / footprints 168-174 of 714")
	)
	(layers
		(0 "F.Cu" signal "TOP")
		(4 "In1.Cu" signal "02_GND")
		(6 "In2.Cu" signal "03_SIG")
		(8 "In3.Cu" signal "04_SIG")
		(10 "In4.Cu" signal "05_GND")
		(12 "In5.Cu" signal "06_PWR1")
		(14 "In6.Cu" signal "07_SIG")
		(16 "In7.Cu" signal "08_SIG")
		(18 "In8.Cu" signal "09_GND")
		(2 "B.Cu" signal "BOTTOM")
		(9 "F.Adhes" user "F.Adhesive")
		(11 "B.Adhes" user "B.Adhesive")
		(13 "F.Paste" user "Package Geometry/Pastemask Top")
		(15 "B.Paste" user "Package Geometry/Pastemask Bottom")
		(5 "F.SilkS" user "Ref Des/Silkscreen Top")
		(7 "B.SilkS" user "Ref Des/Silkscreen Bottom")
		(1 "F.Mask" user "Board Geometry/Soldermask Top")
		(3 "B.Mask" user "Board Geometry/Soldermask Bottom")
		(17 "Dwgs.User" user "User.Drawings")
		(19 "Cmts.User" user "User.Comments")
		(21 "Eco1.User" user "User.Eco1")
		(23 "Eco2.User" user "User.Eco2")
		(25 "Edge.Cuts" user "Board Geometry/Outline")
		(27 "Margin" user)
		(31 "F.CrtYd" user "Package Geometry/Place Bound Top")
		(29 "B.CrtYd" user "Package Geometry/Place Bound Bottom")
		(35 "F.Fab" user "Ref Des/Assembly Top")
		(33 "B.Fab" user "Ref Des/Assembly Bottom")
		(45 "User.4" user "COMPVAL_TYPE_BOTTOM")
	)
	(footprint ""
		(layer "F.Cu")
		(at 58.928 49.784 180)
		(property "Reference" "L21"
			(at 3.175 3.27533 0)
			(unlocked yes)
			(layer "F.SilkS")
			(effects
				(font
					(size 0.7874 0.5842)
					(thickness 0.127)
				)
				(justify left)
			)
		)
		(property "Value" "3.3UH"
			(at -0.4826 -0.14732 180)
			(unlocked yes)
			(layer "F.Fab")
			(hide yes)
			(effects
				(font
					(size 1.27 0.9652)
					(thickness 0.000001)
				)
				(justify left)
			)
		)
		(property "Device Type" "INDS0062"
			(at -0.4826 -0.14732 180)
			(unlocked yes)
			(layer "F.Fab")
			(hide yes)
			(effects
				(font
					(size 1.27 0.9652)
					(thickness 0.000001)
				)
				(justify left)
			)
		)
		(duplicate_pad_numbers_are_jumpers no)
		(fp_line
			(start 2.413 2.413)
			(end 0.1397 2.413)
			(stroke
				(width 0.1524)
				(type default)
			)
			(layer "F.SilkS")
		)
		(fp_line
			(start 2.413 2.413)
			(end -2.413 2.413)
			(stroke
				(width 0.1524)
				(type default)
			)
			(layer "F.SilkS")
		)
		(fp_line
			(start 2.413 -2.413)
			(end 2.413 2.413)
			(stroke
				(width 0.1524)
				(type default)
			)
			(layer "F.SilkS")
		)
		(fp_line
			(start -0.5334 -2.413)
			(end 0.2794 -2.413)
			(stroke
				(width 0.1524)
				(type default)
			)
			(layer "F.SilkS")
		)
		(fp_line
			(start -1.0287 2.413)
			(end -2.413 2.413)
			(stroke
				(width 0.1524)
				(type default)
			)
			(layer "F.SilkS")
		)
		(fp_line
			(start -2.413 2.413)
			(end -2.413 -1.970126)
			(stroke
				(width 0.1524)
				(type default)
			)
			(layer "F.SilkS")
		)
		(fp_line
			(start -2.413 2.413)
			(end -2.413 -2.413)
			(stroke
				(width 0.1524)
				(type default)
			)
			(layer "F.SilkS")
		)
		(fp_line
			(start -2.413 -2.413)
			(end 2.413 -2.413)
			(stroke
				(width 0.1524)
				(type default)
			)
			(layer "F.SilkS")
		)
		(fp_poly
			(pts
				(xy -2.54 2.54) (xy 2.54 2.54) (xy 2.54 -2.54) (xy -2.54 -2.54)
			)
			(stroke
				(width 0)
				(type default)
			)
			(fill no)
			(layer "F.CrtYd")
		)
		(fp_line
			(start 2.1463 2.1463)
			(end 2.1463 -2.1463)
			(stroke
				(width 0.1524)
				(type default)
			)
			(layer "F.Fab")
		)
		(fp_line
			(start 2.1463 -2.1463)
			(end -2.1463 -2.1463)
			(stroke
				(width 0.1524)
				(type default)
			)
			(layer "F.Fab")
		)
		(fp_line
			(start -2.1463 2.1463)
			(end 2.1463 2.1463)
			(stroke
				(width 0.1524)
				(type default)
			)
			(layer "F.Fab")
		)
		(fp_line
			(start -2.1463 -2.1463)
			(end -2.1463 2.1463)
			(stroke
				(width 0.1524)
				(type default)
			)
			(layer "F.Fab")
		)
		(pad "1" smd rect
			(at -1.2192 0 180)
			(size 1.3716 3.5814)
			(layers "F.Cu" "F.Mask" "F.Paste")
			(net "11N1952")
		)
		(pad "2" smd rect
			(at 1.2192 0 180)
			(size 1.3716 3.5814)
			(layers "F.Cu" "F.Mask" "F.Paste")
			(net "VDD_5.0V")
		)
	)
	(footprint ""
		(layer "F.Cu")
		(at 20.193 35.687 180)
		(property "Reference" "R62"
			(at 0.73533 -1.5875 90)
			(unlocked yes)
			(layer "F.SilkS")
			(effects
				(font
					(size 0.7874 0.5842)
					(thickness 0.127)
				)
				(justify left)
			)
		)
		(property "Value" "4.75K"
			(at -0.148158 1.3462 270)
			(unlocked yes)
			(layer "F.Fab")
			(hide yes)
			(effects
				(font
					(size 1.27 0.9652)
					(thickness 0.000001)
				)
				(justify left)
			)
		)
		(property "Device Type" "REST4024"
			(at -0.148158 1.3462 270)
			(unlocked yes)
			(layer "F.Fab")
			(hide yes)
			(effects
				(font
					(size 1.27 0.9652)
					(thickness 0.000001)
				)
				(justify left)
			)
		)
		(duplicate_pad_numbers_are_jumpers no)
		(fp_poly
			(pts
				(xy 0.635 1.0668) (xy 0.635 -1.0668) (xy -0.635 -1.0668) (xy -0.635 1.0668)
			)
			(stroke
				(width 0)
				(type default)
			)
			(fill no)
			(layer "F.CrtYd")
		)
		(fp_line
			(start 0.254 0.508)
			(end -0.254 0.508)
			(stroke
				(width 0.0254)
				(type default)
			)
			(layer "F.Fab")
		)
		(fp_line
			(start 0.254 -0.508)
			(end 0.254 0.508)
			(stroke
				(width 0.0254)
				(type default)
			)
			(layer "F.Fab")
		)
		(fp_line
			(start -0.254 0.508)
			(end -0.254 -0.508)
			(stroke
				(width 0.0254)
				(type default)
			)
			(layer "F.Fab")
		)
		(fp_line
			(start -0.254 -0.508)
			(end 0.254 -0.508)
			(stroke
				(width 0.0254)
				(type default)
			)
			(layer "F.Fab")
		)
		(pad "1" smd rect
			(at 0 -0.4191 180)
			(size 0.508 0.5334)
			(layers "F.Cu" "F.Mask" "F.Paste")
			(net "EXT_3.3V")
		)
		(pad "2" smd rect
			(at 0 0.4191 180)
			(size 0.508 0.5334)
			(layers "F.Cu" "F.Mask" "F.Paste")
			(net "CPLD_PGRM_JTAG_TDO")
		)
		(zone
			(layer "F.Cu")
			(hatch none 0.5)
			(connect_pads
				(clearance 0)
			)
			(min_thickness 0.25)
			(keepout
				(tracks not_allowed)
				(vias allowed)
				(pads allowed)
				(copperpour not_allowed)
				(footprints allowed)
			)
			(placement
				(enabled no)
				(sheetname "")
			)
			(fill
				(thermal_gap 0.5)
				(thermal_bridge_width 0.5)
				(island_removal_mode 0)
			)
			(polygon
				(pts
					(xy 20.1676 35.7124) (xy 20.1676 35.6616) (xy 20.2184 35.6616) (xy 20.2184 35.7124)
				)
			)
		)
	)
	(footprint ""
		(layer "F.Cu")
		(at 5.334 23.6728 180)
		(property "Reference" "C242"
			(at 6.45033 2.4638 90)
			(unlocked yes)
			(layer "F.SilkS")
			(effects
				(font
					(size 0.7874 0.5842)
					(thickness 0.127)
				)
				(justify left)
			)
		)
		(property "Value" "220UF"
			(at -0.4826 1.37668 180)
			(unlocked yes)
			(layer "F.Fab")
			(hide yes)
			(effects
				(font
					(size 1.27 0.9652)
					(thickness 0.000001)
				)
				(justify left)
			)
		)
		(property "Device Type" "CAPE0005"
			(at -0.4826 1.37668 180)
			(unlocked yes)
			(layer "F.Fab")
			(hide yes)
			(effects
				(font
					(size 1.27 0.9652)
					(thickness 0.000001)
				)
				(justify left)
			)
		)
		(duplicate_pad_numbers_are_jumpers no)
		(fp_line
			(start 5.588 5.588)
			(end 5.588 -3.302)
			(stroke
				(width 0.2032)
				(type default)
			)
			(layer "F.SilkS")
		)
		(fp_line
			(start 5.588 5.588)
			(end 5.588 -3.302)
			(stroke
				(width 0.2032)
				(type default)
			)
			(layer "F.SilkS")
		)
		(fp_line
			(start 5.588 -3.302)
			(end 3.302 -5.588)
			(stroke
				(width 0.2032)
				(type default)
			)
			(layer "F.SilkS")
		)
		(fp_line
			(start 5.588 -3.302)
			(end 3.302 -5.588)
			(stroke
				(width 0.2032)
				(type default)
			)
			(layer "F.SilkS")
		)
		(fp_line
			(start 3.302 -5.588)
			(end 1.640637 -5.588)
			(stroke
				(width 0.2032)
				(type default)
			)
			(layer "F.SilkS")
		)
		(fp_line
			(start 3.302 -5.588)
			(end 1.27 -5.588)
			(stroke
				(width 0.2032)
				(type default)
			)
			(layer "F.SilkS")
		)
		(fp_line
			(start 2.2606 -7.0104)
			(end 2.2606 -5.7404)
			(stroke
				(width 0.2032)
				(type default)
			)
			(layer "F.SilkS")
		)
		(fp_line
			(start 2.2606 -7.0104)
			(end 2.2606 -5.7404)
			(stroke
				(width 0.2032)
				(type default)
			)
			(layer "F.SilkS")
		)
		(fp_line
			(start 2.001825 -6.3754)
			(end 2.8956 -6.3754)
			(stroke
				(width 0.2032)
				(type default)
			)
			(layer "F.SilkS")
		)
		(fp_line
			(start 1.6256 -6.3754)
			(end 2.8956 -6.3754)
			(stroke
				(width 0.2032)
				(type default)
			)
			(layer "F.SilkS")
		)
		(fp_line
			(start 1.3081 5.588)
			(end 5.588 5.588)
			(stroke
				(width 0.2032)
				(type default)
			)
			(layer "F.SilkS")
		)
		(fp_line
			(start 1.27 5.588)
			(end 5.588 5.588)
			(stroke
				(width 0.2032)
				(type default)
			)
			(layer "F.SilkS")
		)
		(fp_line
			(start -1.27 -5.588)
			(end -3.302 -5.588)
			(stroke
				(width 0.2032)
				(type default)
			)
			(layer "F.SilkS")
		)
		(fp_line
			(start -1.3081 -5.588)
			(end -3.302 -5.588)
			(stroke
				(width 0.2032)
				(type default)
			)
			(layer "F.SilkS")
		)
		(fp_line
			(start -3.302 -5.588)
			(end -4.736389 -4.153611)
			(stroke
				(width 0.2032)
				(type default)
			)
			(layer "F.SilkS")
		)
		(fp_line
			(start -3.302 -5.588)
			(end -5.588 -3.302)
			(stroke
				(width 0.2032)
				(type default)
			)
			(layer "F.SilkS")
		)
		(fp_line
			(start -5.588 5.588)
			(end -1.27 5.588)
			(stroke
				(width 0.2032)
				(type default)
			)
			(layer "F.SilkS")
		)
		(fp_line
			(start -5.588 -3.302)
			(end -5.588 5.588)
			(stroke
				(width 0.2032)
				(type default)
			)
			(layer "F.SilkS")
		)
		(fp_line
			(start -5.588 -3.302)
			(end -5.588 5.588)
			(stroke
				(width 0.2032)
				(type default)
			)
			(layer "F.SilkS")
		)
		(fp_poly
			(pts
				(xy -5.7912 -5.842) (xy -1.524 -5.842) (xy -1.524 -7.112) (xy 1.524 -7.112) (xy 1.524 -5.842) (xy 5.254168 -5.842)
				(xy 5.254168 5.842) (xy 1.524 5.842) (xy 1.524 7.112) (xy -1.524 7.112) (xy -1.524 5.842) (xy -5.7912 5.842)
			)
			(stroke
				(width 0)
				(type default)
			)
			(fill no)
			(layer "F.CrtYd")
		)
		(fp_line
			(start 5.2578 5.2578)
			(end 5.2578 -3.2258)
			(stroke
				(width 0.2032)
				(type default)
			)
			(layer "F.Fab")
		)
		(fp_line
			(start 5.2578 -3.2258)
			(end 3.2258 -5.2578)
			(stroke
				(width 0.2032)
				(type default)
			)
			(layer "F.Fab")
		)
		(fp_line
			(start 3.2258 -5.2578)
			(end -3.2258 -5.2578)
			(stroke
				(width 0.2032)
				(type default)
			)
			(layer "F.Fab")
		)
		(fp_line
			(start 0.635 -3.937)
			(end -0.635 -3.937)
			(stroke
				(width 0.2032)
				(type default)
			)
			(layer "F.Fab")
		)
		(fp_line
			(start 0 -4.572)
			(end 0 -3.302)
			(stroke
				(width 0.2032)
				(type default)
			)
			(layer "F.Fab")
		)
		(fp_line
			(start -3.2258 -5.2578)
			(end -5.2578 -3.2258)
			(stroke
				(width 0.2032)
				(type default)
			)
			(layer "F.Fab")
		)
		(fp_line
			(start -5.2578 5.2578)
			(end 5.2578 5.2578)
			(stroke
				(width 0.2032)
				(type default)
			)
			(layer "F.Fab")
		)
		(fp_line
			(start -5.2578 -3.2258)
			(end -5.2578 5.2578)
			(stroke
				(width 0.2032)
				(type default)
			)
			(layer "F.Fab")
		)
		(pad "1" smd rect
			(at 0 -4.3561 180)
			(size 1.905 4.4196)
			(layers "F.Cu" "F.Mask" "F.Paste")
			(net "EXT_12.0V")
		)
		(pad "2" smd rect
			(at 0 4.3561 180)
			(size 1.905 4.4196)
			(layers "F.Cu" "F.Mask" "F.Paste")
			(net "GND")
		)
	)
	(footprint ""
		(layer "F.Cu")
		(at 27.051 12.827 -90)
		(property "Reference" "R139"
			(at 0 0 270)
			(layer "F.SilkS")
			(hide yes)
			(effects
				(font
					(size 1.27 1.27)
				)
			)
		)
		(property "Value" "0"
			(at -0.148158 1.3462 0)
			(unlocked yes)
			(layer "F.Fab")
			(hide yes)
			(effects
				(font
					(size 1.27 0.9652)
					(thickness 0.000001)
				)
				(justify left)
			)
		)
		(property "Device Type" "REST1111"
			(at -0.148158 1.3462 0)
			(unlocked yes)
			(layer "F.Fab")
			(hide yes)
			(effects
				(font
					(size 1.27 0.9652)
					(thickness 0.000001)
				)
				(justify left)
			)
		)
		(duplicate_pad_numbers_are_jumpers no)
		(fp_poly
			(pts
				(xy 0.635 1.0668) (xy 0.635 -1.0668) (xy -0.635 -1.0668) (xy -0.635 1.0668)
			)
			(stroke
				(width 0)
				(type default)
			)
			(fill no)
			(layer "F.CrtYd")
		)
		(fp_line
			(start -0.254 0.508)
			(end -0.254 -0.508)
			(stroke
				(width 0.0254)
				(type default)
			)
			(layer "F.Fab")
		)
		(fp_line
			(start 0.254 0.508)
			(end -0.254 0.508)
			(stroke
				(width 0.0254)
				(type default)
			)
			(layer "F.Fab")
		)
		(fp_line
			(start -0.254 -0.508)
			(end 0.254 -0.508)
			(stroke
				(width 0.0254)
				(type default)
			)
			(layer "F.Fab")
		)
		(fp_line
			(start 0.254 -0.508)
			(end 0.254 0.508)
			(stroke
				(width 0.0254)
				(type default)
			)
			(layer "F.Fab")
		)
		(pad "1" smd rect
			(at 0 -0.4191 270)
			(size 0.508 0.5334)
			(layers "F.Cu" "F.Mask" "F.Paste")
			(net "_PSU_I2C_SDA")
		)
		(pad "2" smd rect
			(at 0 0.4191 270)
			(size 0.508 0.5334)
			(layers "F.Cu" "F.Mask" "F.Paste")
			(net "PSU_I2C_SDA")
		)
		(zone
			(layer "F.Cu")
			(hatch none 0.5)
			(connect_pads
				(clearance 0)
			)
			(min_thickness 0.25)
			(keepout
				(tracks not_allowed)
				(vias allowed)
				(pads allowed)
				(copperpour not_allowed)
				(footprints allowed)
			)
			(placement
				(enabled no)
				(sheetname "")
			)
			(fill
				(thermal_gap 0.5)
				(thermal_bridge_width 0.5)
				(island_removal_mode 0)
			)
			(polygon
				(pts
					(xy 27.0764 12.8524) (xy 27.0256 12.8524) (xy 27.0256 12.8016) (xy 27.0764 12.8016)
				)
			)
		)
	)
	(footprint ""
		(layer "F.Cu")
		(at 76.327 11.557 180)
		(property "Reference" "R361"
			(at -0.15367 -1.905 90)
			(unlocked yes)
			(layer "F.SilkS")
			(effects
				(font
					(size 0.7874 0.5842)
					(thickness 0.127)
				)
				(justify left)
			)
		)
		(property "Value" "100"
			(at -0.148158 1.3462 270)
			(unlocked yes)
			(layer "F.Fab")
			(hide yes)
			(effects
				(font
					(size 1.27 0.9652)
					(thickness 0.000001)
				)
				(justify left)
			)
		)
		(property "Device Type" "REST4030"
			(at -0.148158 1.3462 270)
			(unlocked yes)
			(layer "F.Fab")
			(hide yes)
			(effects
				(font
					(size 1.27 0.9652)
					(thickness 0.000001)
				)
				(justify left)
			)
		)
		(duplicate_pad_numbers_are_jumpers no)
		(fp_poly
			(pts
				(xy 0.635 1.0668) (xy 0.635 -1.0668) (xy -0.635 -1.0668) (xy -0.635 1.0668)
			)
			(stroke
				(width 0)
				(type default)
			)
			(fill no)
			(layer "F.CrtYd")
		)
		(fp_line
			(start 0.254 0.508)
			(end -0.254 0.508)
			(stroke
				(width 0.0254)
				(type default)
			)
			(layer "F.Fab")
		)
		(fp_line
			(start 0.254 -0.508)
			(end 0.254 0.508)
			(stroke
				(width 0.0254)
				(type default)
			)
			(layer "F.Fab")
		)
		(fp_line
			(start -0.254 0.508)
			(end -0.254 -0.508)
			(stroke
				(width 0.0254)
				(type default)
			)
			(layer "F.Fab")
		)
		(fp_line
			(start -0.254 -0.508)
			(end 0.254 -0.508)
			(stroke
				(width 0.0254)
				(type default)
			)
			(layer "F.Fab")
		)
		(pad "1" smd rect
			(at 0 -0.4191 180)
			(size 0.508 0.5334)
			(layers "F.Cu" "F.Mask" "F.Paste")
			(net "GND")
		)
		(pad "2" smd rect
			(at 0 0.4191 180)
			(size 0.508 0.5334)
			(layers "F.Cu" "F.Mask" "F.Paste")
			(net "DDR0_32A_VREF1B")
		)
		(zone
			(layer "F.Cu")
			(hatch none 0.5)
			(connect_pads
				(clearance 0)
			)
			(min_thickness 0.25)
			(keepout
				(tracks not_allowed)
				(vias allowed)
				(pads allowed)
				(copperpour not_allowed)
				(footprints allowed)
			)
			(placement
				(enabled no)
				(sheetname "")
			)
			(fill
				(thermal_gap 0.5)
				(thermal_bridge_width 0.5)
				(island_removal_mode 0)
			)
			(polygon
				(pts
					(xy 76.3016 11.5824) (xy 76.3016 11.5316) (xy 76.3524 11.5316) (xy 76.3524 11.5824)
				)
			)
		)
	)
	(footprint ""
		(layer "F.Cu")
		(at 27.178 10.414 -90)
		(property "Reference" "R262"
			(at 0 0 270)
			(layer "F.SilkS")
			(hide yes)
			(effects
				(font
					(size 1.27 1.27)
				)
			)
		)
		(property "Value" "39.0"
			(at -0.148158 1.3462 0)
			(unlocked yes)
			(layer "F.Fab")
			(hide yes)
			(effects
				(font
					(size 1.27 0.9652)
					(thickness 0.000001)
				)
				(justify left)
			)
		)
		(property "Device Type" "REST0108"
			(at -0.148158 1.3462 0)
			(unlocked yes)
			(layer "F.Fab")
			(hide yes)
			(effects
				(font
					(size 1.27 0.9652)
					(thickness 0.000001)
				)
				(justify left)
			)
		)
		(duplicate_pad_numbers_are_jumpers no)
		(fp_poly
			(pts
				(xy 0.635 1.0668) (xy 0.635 -1.0668) (xy -0.635 -1.0668) (xy -0.635 1.0668)
			)
			(stroke
				(width 0)
				(type default)
			)
			(fill no)
			(layer "F.CrtYd")
		)
		(fp_line
			(start -0.254 0.508)
			(end -0.254 -0.508)
			(stroke
				(width 0.0254)
				(type default)
			)
			(layer "F.Fab")
		)
		(fp_line
			(start 0.254 0.508)
			(end -0.254 0.508)
			(stroke
				(width 0.0254)
				(type default)
			)
			(layer "F.Fab")
		)
		(fp_line
			(start -0.254 -0.508)
			(end 0.254 -0.508)
			(stroke
				(width 0.0254)
				(type default)
			)
			(layer "F.Fab")
		)
		(fp_line
			(start 0.254 -0.508)
			(end 0.254 0.508)
			(stroke
				(width 0.0254)
				(type default)
			)
			(layer "F.Fab")
		)
		(pad "1" smd rect
			(at 0 -0.4191 270)
			(size 0.508 0.5334)
			(layers "F.Cu" "F.Mask" "F.Paste")
			(net "_PGRM_JTAG_TDO")
		)
		(pad "2" smd rect
			(at 0 0.4191 270)
			(size 0.508 0.5334)
			(layers "F.Cu" "F.Mask" "F.Paste")
			(net "PGRM_JTAG_TDO")
		)
		(zone
			(layer "F.Cu")
			(hatch none 0.5)
			(connect_pads
				(clearance 0)
			)
			(min_thickness 0.25)
			(keepout
				(tracks not_allowed)
				(vias allowed)
				(pads allowed)
				(copperpour not_allowed)
				(footprints allowed)
			)
			(placement
				(enabled no)
				(sheetname "")
			)
			(fill
				(thermal_gap 0.5)
				(thermal_bridge_width 0.5)
				(island_removal_mode 0)
			)
			(polygon
				(pts
					(xy 27.2034 10.4394) (xy 27.1526 10.4394) (xy 27.1526 10.3886) (xy 27.2034 10.3886)
				)
			)
		)
	)
	(footprint ""
		(layer "F.Cu")
		(at 35.941 8.636 90)
		(property "Reference" "R134"
			(at 0 0 90)
			(layer "F.SilkS")
			(hide yes)
			(effects
				(font
					(size 1.27 1.27)
				)
			)
		)
		(property "Value" "0"
			(at -0.148158 1.3462 180)
			(unlocked yes)
			(layer "F.Fab")
			(hide yes)
			(effects
				(font
					(size 1.27 0.9652)
					(thickness 0.000001)
				)
				(justify left)
			)
		)
		(property "Device Type" "REST1111"
			(at -0.148158 1.3462 180)
			(unlocked yes)
			(layer "F.Fab")
			(hide yes)
			(effects
				(font
					(size 1.27 0.9652)
					(thickness 0.000001)
				)
				(justify left)
			)
		)
		(duplicate_pad_numbers_are_jumpers no)
		(fp_poly
			(pts
				(xy 0.635 1.0668) (xy 0.635 -1.0668) (xy -0.635 -1.0668) (xy -0.635 1.0668)
			)
			(stroke
				(width 0)
				(type default)
			)
			(fill no)
			(layer "F.CrtYd")
		)
		(fp_line
			(start 0.254 -0.508)
			(end 0.254 0.508)
			(stroke
				(width 0.0254)
				(type default)
			)
			(layer "F.Fab")
		)
		(fp_line
			(start -0.254 -0.508)
			(end 0.254 -0.508)
			(stroke
				(width 0.0254)
				(type default)
			)
			(layer "F.Fab")
		)
		(fp_line
			(start 0.254 0.508)
			(end -0.254 0.508)
			(stroke
				(width 0.0254)
				(type default)
			)
			(layer "F.Fab")
		)
		(fp_line
			(start -0.254 0.508)
			(end -0.254 -0.508)
			(stroke
				(width 0.0254)
				(type default)
			)
			(layer "F.Fab")
		)
		(pad "1" smd rect
			(at 0 -0.4191 90)
			(size 0.508 0.5334)
			(layers "F.Cu" "F.Mask" "F.Paste")
			(net "3N2302")
		)
		(pad "2" smd rect
			(at 0 0.4191 90)
			(size 0.508 0.5334)
			(layers "F.Cu" "F.Mask" "F.Paste")
			(net "NFP_CLK_REF_P")
		)
		(zone
			(layer "F.Cu")
			(hatch none 0.5)
			(connect_pads
				(clearance 0)
			)
			(min_thickness 0.25)
			(keepout
				(tracks not_allowed)
				(vias allowed)
				(pads allowed)
				(copperpour not_allowed)
				(footprints allowed)
			)
			(placement
				(enabled no)
				(sheetname "")
			)
			(fill
				(thermal_gap 0.5)
				(thermal_bridge_width 0.5)
				(island_removal_mode 0)
			)
			(polygon
				(pts
					(xy 35.9156 8.6106) (xy 35.9664 8.6106) (xy 35.9664 8.6614) (xy 35.9156 8.6614)
				)
			)
		)
	)
)
